# BASEBOARD_FAB2 (Tioga Pass) — schematic netlist excerpt (pin names and nets, part order shuffled) for the footprints in the layout excerpt that follows; sources: Cadence DE-HDL packaged netlist, KiCad conversion of Wiwynn_Tioga_Pass_MB.brd

C9M2  CAP_A  0.01UF 25V 10% X7R  pkg 0402V  page 100 : A = M_K_CPU_VREF ; B = GND
R8C6  RES  4.75K 1% CHIP  pkg 0402  page 133 : A = P3V3_STBY ; B = FM_BIOS_POST_CMPLT_N
C14W1  CAP_A  0.1UF 16V 10% X7R  pkg 0402V  page 248 : A = P3V3 ; B = GND

(kicad_pcb
	(version 20260206)
	(generator "pcbnew")
	(generator_version "10.0")
	(general
		(thickness 1.6)
		(legacy_teardrops no)
	)
	(paper "A4")
	(title_block
		(title "Wiwynn_Tioga_Pass_MB.brd")
		(comment 1 "Tioga Pass / footprints 4336-4338 of 4770")
	)
	(layers
		(0 "F.Cu" signal "TOP")
		(4 "In1.Cu" signal "L2GND")
		(6 "In2.Cu" signal "L3")
		(8 "In3.Cu" signal "L4GND")
		(10 "In4.Cu" signal "L5")
		(12 "In5.Cu" signal "L6GND")
		(14 "In6.Cu" signal "L7VCC")
		(16 "In7.Cu" signal "L8VCC")
		(18 "In8.Cu" signal "L9GND")
		(20 "In9.Cu" signal "L10")
		(22 "In10.Cu" signal "L11GND")
		(24 "In11.Cu" signal "L12")
		(26 "In12.Cu" signal "L13GND")
		(2 "B.Cu" signal "BOTTOM")
		(9 "F.Adhes" user "F.Adhesive")
		(11 "B.Adhes" user "B.Adhesive")
		(13 "F.Paste" user "Package Geometry/Pastemask Top")
		(15 "B.Paste" user "Package Geometry/Pastemask Bottom")
		(5 "F.SilkS" user "Ref Des/Silkscreen Top")
		(7 "B.SilkS" user "Ref Des/Silkscreen Bottom")
		(1 "F.Mask" user "Board Geometry/Soldermask Top")
		(3 "B.Mask" user "Board Geometry/Soldermask Bottom")
		(17 "Dwgs.User" user "User.Drawings")
		(19 "Cmts.User" user "User.Comments")
		(21 "Eco1.User" user "User.Eco1")
		(23 "Eco2.User" user "User.Eco2")
		(25 "Edge.Cuts" user "Board Geometry/Outline")
		(27 "Margin" user)
		(31 "F.CrtYd" user "Package Geometry/Place Bound Top")
		(29 "B.CrtYd" user "Package Geometry/Place Bound Bottom")
		(35 "F.Fab" user "Ref Des/Assembly Top")
		(33 "B.Fab" user "Ref Des/Assembly Bottom")
	)
	(footprint ""
		(layer "B.Cu")
		(at 27.023568 -134.874 180)
		(property "Reference" "C9M2"
			(at 0 0 0)
			(layer "B.SilkS")
			(hide yes)
			(effects
				(font
					(size 1.27 1.27)
				)
				(justify mirror)
			)
		)
		(property "Value" ""
			(at 0 0 0)
			(layer "B.Fab")
			(effects
				(font
					(size 1.27 1.27)
				)
				(justify mirror)
			)
		)
		(duplicate_pad_numbers_are_jumpers no)
		(fp_poly
			(pts
				(xy -0.3048 -0.1016) (xy -0.3048 0.9906) (xy 0.3048 0.9906) (xy 0.3048 -0.1016)
			)
			(stroke
				(width 0)
				(type default)
			)
			(fill no)
			(layer "B.CrtYd")
		)
		(fp_line
			(start 0.3048 0.9906)
			(end -0.3048 0.9906)
			(stroke
				(width 0.1)
				(type default)
			)
			(layer "B.Fab")
		)
		(fp_line
			(start 0.3048 -0.1016)
			(end 0.3048 0.9906)
			(stroke
				(width 0.1)
				(type default)
			)
			(layer "B.Fab")
		)
		(fp_line
			(start -0.3048 0.9906)
			(end -0.3048 -0.1016)
			(stroke
				(width 0.1)
				(type default)
			)
			(layer "B.Fab")
		)
		(fp_line
			(start -0.3048 -0.1016)
			(end 0.3048 -0.1016)
			(stroke
				(width 0.1)
				(type default)
			)
			(layer "B.Fab")
		)
		(pad "1" smd rect
			(at 0 0)
			(size 0.508 0.508)
			(layers "B.Cu" "B.Mask" "B.Paste")
			(net "M_K_CPU_VREF")
		)
		(pad "2" smd rect
			(at 0 0.889)
			(size 0.508 0.508)
			(layers "B.Cu" "B.Mask" "B.Paste")
			(net "GND")
		)
		(zone
			(layer "B.Cu")
			(hatch none 0.5)
			(connect_pads
				(clearance 0)
			)
			(min_thickness 0.25)
			(keepout
				(tracks not_allowed)
				(vias allowed)
				(pads allowed)
				(copperpour not_allowed)
				(footprints allowed)
			)
			(placement
				(enabled no)
				(sheetname "")
			)
			(fill
				(thermal_gap 0.5)
				(thermal_bridge_width 0.5)
				(island_removal_mode 0)
			)
			(polygon
				(pts
					(xy 26.769568 -135.509) (xy 27.277568 -135.509) (xy 27.277568 -135.128) (xy 26.769568 -135.128)
				)
			)
		)
		(zone
			(layer "B.Cu")
			(hatch none 0.5)
			(connect_pads
				(clearance 0)
			)
			(min_thickness 0.25)
			(keepout
				(tracks allowed)
				(vias not_allowed)
				(pads allowed)
				(copperpour not_allowed)
				(footprints allowed)
			)
			(placement
				(enabled no)
				(sheetname "")
			)
			(fill
				(thermal_gap 0.5)
				(thermal_bridge_width 0.5)
				(island_removal_mode 0)
			)
			(polygon
				(pts
					(xy 26.769568 -135.128) (xy 27.277568 -135.128) (xy 27.277568 -135.509) (xy 26.769568 -135.509)
				)
			)
		)
	)
	(footprint ""
		(layer "B.Cu")
		(at 385.90474 -83.22056 90)
		(property "Reference" "C14W1"
			(at 0.8382 -0.67818 90)
			(unlocked yes)
			(layer "B.SilkS")
			(effects
				(font
					(size 0.4064 0.254)
					(thickness 0.1524)
				)
				(justify left mirror)
			)
		)
		(property "Value" ""
			(at 0 0 90)
			(layer "B.Fab")
			(effects
				(font
					(size 1.27 1.27)
				)
				(justify mirror)
			)
		)
		(duplicate_pad_numbers_are_jumpers no)
		(fp_poly
			(pts
				(xy -0.3048 -0.1016) (xy -0.3048 0.9906) (xy 0.3048 0.9906) (xy 0.3048 -0.1016)
			)
			(stroke
				(width 0)
				(type default)
			)
			(fill no)
			(layer "B.CrtYd")
		)
		(fp_line
			(start 0.3048 -0.1016)
			(end 0.3048 0.9906)
			(stroke
				(width 0.1)
				(type default)
			)
			(layer "B.Fab")
		)
		(fp_line
			(start -0.3048 -0.1016)
			(end 0.3048 -0.1016)
			(stroke
				(width 0.1)
				(type default)
			)
			(layer "B.Fab")
		)
		(fp_line
			(start 0.3048 0.9906)
			(end -0.3048 0.9906)
			(stroke
				(width 0.1)
				(type default)
			)
			(layer "B.Fab")
		)
		(fp_line
			(start -0.3048 0.9906)
			(end -0.3048 -0.1016)
			(stroke
				(width 0.1)
				(type default)
			)
			(layer "B.Fab")
		)
		(pad "1" smd rect
			(at 0 0 270)
			(size 0.508 0.508)
			(layers "B.Cu" "B.Mask" "B.Paste")
			(net "P3V3")
		)
		(pad "2" smd rect
			(at 0 0.889 270)
			(size 0.508 0.508)
			(layers "B.Cu" "B.Mask" "B.Paste")
			(net "GND")
		)
		(zone
			(layer "B.Cu")
			(hatch none 0.5)
			(connect_pads
				(clearance 0)
			)
			(min_thickness 0.25)
			(keepout
				(tracks allowed)
				(vias not_allowed)
				(pads allowed)
				(copperpour not_allowed)
				(footprints allowed)
			)
			(placement
				(enabled no)
				(sheetname "")
			)
			(fill
				(thermal_gap 0.5)
				(thermal_bridge_width 0.5)
				(island_removal_mode 0)
			)
			(polygon
				(pts
					(xy 386.15874 -83.47456) (xy 386.15874 -82.96656) (xy 386.53974 -82.96656) (xy 386.53974 -83.47456)
				)
			)
		)
		(zone
			(layer "B.Cu")
			(hatch none 0.5)
			(connect_pads
				(clearance 0)
			)
			(min_thickness 0.25)
			(keepout
				(tracks not_allowed)
				(vias allowed)
				(pads allowed)
				(copperpour not_allowed)
				(footprints allowed)
			)
			(placement
				(enabled no)
				(sheetname "")
			)
			(fill
				(thermal_gap 0.5)
				(thermal_bridge_width 0.5)
				(island_removal_mode 0)
			)
			(polygon
				(pts
					(xy 386.53974 -83.47456) (xy 386.53974 -82.96656) (xy 386.15874 -82.96656) (xy 386.15874 -83.47456)
				)
			)
		)
	)
	(footprint ""
		(layer "B.Cu")
		(at 401.193 -107.1245 180)
		(property "Reference" "R8C6"
			(at 0 0 0)
			(layer "B.SilkS")
			(hide yes)
			(effects
				(font
					(size 1.27 1.27)
				)
				(justify mirror)
			)
		)
		(property "Value" ""
			(at 0 0 0)
			(layer "B.Fab")
			(effects
				(font
					(size 1.27 1.27)
				)
				(justify mirror)
			)
		)
		(duplicate_pad_numbers_are_jumpers no)
		(fp_poly
			(pts
				(xy 0.2794 -0.1016) (xy -0.2794 -0.1016) (xy -0.2794 0.9906) (xy 0.2794 0.9906)
			)
			(stroke
				(width 0)
				(type default)
			)
			(fill no)
			(layer "B.CrtYd")
		)
		(fp_line
			(start 0.2794 0.9906)
			(end -0.2794 0.9906)
			(stroke
				(width 0.1)
				(type default)
			)
			(layer "B.Fab")
		)
		(fp_line
			(start 0.2794 -0.1016)
			(end 0.2794 0.9906)
			(stroke
				(width 0.1)
				(type default)
			)
			(layer "B.Fab")
		)
		(fp_line
			(start -0.2794 0.9906)
			(end -0.2794 -0.1016)
			(stroke
				(width 0.1)
				(type default)
			)
			(layer "B.Fab")
		)
		(fp_line
			(start -0.2794 -0.1016)
			(end 0.2794 -0.1016)
			(stroke
				(width 0.1)
				(type default)
			)
			(layer "B.Fab")
		)
		(pad "1" smd rect
			(at 0 0)
			(size 0.508 0.508)
			(layers "B.Cu" "B.Mask" "B.Paste")
			(net "P3V3_STBY")
		)
		(pad "2" smd rect
			(at 0 0.889)
			(size 0.508 0.508)
			(layers "B.Cu" "B.Mask" "B.Paste")
			(net "FM_BIOS_POST_CMPLT_N")
		)
		(zone
			(layer "B.Cu")
			(hatch none 0.5)
			(connect_pads
				(clearance 0)
			)
			(min_thickness 0.25)
			(keepout
				(tracks not_allowed)
				(vias allowed)
				(pads allowed)
				(copperpour not_allowed)
				(footprints allowed)
			)
			(placement
				(enabled no)
				(sheetname "")
			)
			(fill
				(thermal_gap 0.5)
				(thermal_bridge_width 0.5)
				(island_removal_mode 0)
			)
			(polygon
				(pts
					(xy 400.939 -107.7595) (xy 401.447 -107.7595) (xy 401.447 -107.3785) (xy 400.939 -107.3785)
				)
			)
		)
		(zone
			(layer "B.Cu")
			(hatch none 0.5)
			(connect_pads
				(clearance 0)
			)
			(min_thickness 0.25)
			(keepout
				(tracks allowed)
				(vias not_allowed)
				(pads allowed)
				(copperpour not_allowed)
				(footprints allowed)
			)
			(placement
				(enabled no)
				(sheetname "")
			)
			(fill
				(thermal_gap 0.5)
				(thermal_bridge_width 0.5)
				(island_removal_mode 0)
			)
			(polygon
				(pts
					(xy 400.939 -107.3785) (xy 401.447 -107.3785) (xy 401.447 -107.7595) (xy 400.939 -107.7595)
				)
			)
		)
	)
)
